(kicad_pcb
	(version 20260206)
	(generator "pcbnew")
	(generator_version "10.0")
	(general
		(thickness 1.6)
		(legacy_teardrops no)
	)
	(paper "A4")
	(title_block
		(title "peb — Lightning_PEB_BRD.brd")
		(comment 1 "Lightning (Wiwynn / Facebook NVMe JBOF) / footprints 928-934 of 2563")
	)
	(layers
		(0 "F.Cu" signal "TOP")
		(4 "In1.Cu" signal "L2GND")
		(6 "In2.Cu" signal "L3")
		(8 "In3.Cu" signal "L4VCC")
		(10 "In4.Cu" signal "L5VCC")
		(12 "In5.Cu" signal "L6")
		(14 "In6.Cu" signal "L7GND")
		(2 "B.Cu" signal "BOTTOM")
		(9 "F.Adhes" user "F.Adhesive")
		(11 "B.Adhes" user "B.Adhesive")
		(13 "F.Paste" user "Package Geometry/Pastemask Top")
		(15 "B.Paste" user "Package Geometry/Pastemask Bottom")
		(5 "F.SilkS" user "Ref Des/Silkscreen Top")
		(7 "B.SilkS" user "Ref Des/Silkscreen Bottom")
		(1 "F.Mask" user "Board Geometry/Soldermask Top")
		(3 "B.Mask" user "Board Geometry/Soldermask Bottom")
		(17 "Dwgs.User" user "User.Drawings")
		(19 "Cmts.User" user "User.Comments")
		(21 "Eco1.User" user "User.Eco1")
		(23 "Eco2.User" user "User.Eco2")
		(25 "Edge.Cuts" user "Board Geometry/Outline")
		(27 "Margin" user)
		(31 "F.CrtYd" user "Package Geometry/Place Bound Top")
		(29 "B.CrtYd" user "Package Geometry/Place Bound Bottom")
		(35 "F.Fab" user "Ref Des/Assembly Top")
		(33 "B.Fab" user "Ref Des/Assembly Bottom")
	)
	(footprint ""
		(layer "F.Cu")
		(at 325.918322 -33.45942)
		(property "Reference" "C50"
			(at 0 0 0)
			(layer "F.SilkS")
			(hide yes)
			(effects
				(font
					(size 1.27 1.27)
				)
			)
		)
		(property "Value" "SCD22U10V2KX-1GP"
			(at 1.1811 -2.7051 0)
			(unlocked yes)
			(layer "F.Fab")
			(hide yes)
			(effects
				(font
					(size 1.016 1.016)
					(thickness 0.1524)
				)
			)
		)
		(property "Device Type" "C402H22"
			(at 1.1811 -4.2291 0)
			(unlocked yes)
			(layer "F.Fab")
			(hide yes)
			(effects
				(font
					(size 1.016 1.016)
					(thickness 0.1524)
				)
			)
		)
		(duplicate_pad_numbers_are_jumpers no)
		(fp_rect
			(start -0.4318 0.9525)
			(end 0.4318 -0.9525)
			(stroke
				(width 0)
				(type default)
			)
			(fill no)
			(layer "F.CrtYd")
		)
		(fp_rect
			(start -0.4318 0.9525)
			(end 0.4318 -0.9525)
			(stroke
				(width 0)
				(type default)
			)
			(fill no)
			(layer "F.Fab")
		)
		(pad "1" smd custom
			(at 0 -0.4445)
			(size 0.1524 0.1524)
			(layers "F.Cu" "F.Mask" "F.Paste")
			(net "PCIE_TX_CAP_P14")
			(options
				(clearance outline)
				(anchor circle)
			)
			(primitives
				(gr_poly
					(pts
						(arc
							(start 0.3048 -0.2032)
							(mid 0.275042 -0.275042)
							(end 0.2032 -0.3048)
						)
						(arc
							(start -0.2032 -0.3048)
							(mid -0.275042 -0.275042)
							(end -0.3048 -0.2032)
						)
						(arc
							(start -0.3048 0.2032)
							(mid -0.275042 0.275042)
							(end -0.2032 0.3048)
						)
						(arc
							(start 0.2032 0.3048)
							(mid 0.275042 0.275042)
							(end 0.3048 0.2032)
						)
					)
					(width 0)
					(fill yes)
				)
			)
		)
		(pad "2" smd custom
			(at 0 0.4445)
			(size 0.1524 0.1524)
			(layers "F.Cu" "F.Mask" "F.Paste")
			(net "PCIE_TX_P14")
			(options
				(clearance outline)
				(anchor circle)
			)
			(primitives
				(gr_poly
					(pts
						(arc
							(start 0.3048 -0.2032)
							(mid 0.275042 -0.275042)
							(end 0.2032 -0.3048)
						)
						(arc
							(start -0.2032 -0.3048)
							(mid -0.275042 -0.275042)
							(end -0.3048 -0.2032)
						)
						(arc
							(start -0.3048 0.2032)
							(mid -0.275042 0.275042)
							(end -0.2032 0.3048)
						)
						(arc
							(start 0.2032 0.3048)
							(mid 0.275042 0.275042)
							(end 0.3048 0.2032)
						)
					)
					(width 0)
					(fill yes)
				)
			)
		)
	)
	(footprint ""
		(layer "F.Cu")
		(at 20.3454 -184.7342 -90)
		(property "Reference" "R2123"
			(at 0 0 270)
			(layer "F.SilkS")
			(hide yes)
			(effects
				(font
					(size 1.27 1.27)
				)
			)
		)
		(property "Value" "10R2F-L-GP"
			(at 0.064008 -3.993896 270)
			(unlocked yes)
			(layer "F.Fab")
			(hide yes)
			(effects
				(font
					(size 1.016 1.016)
					(thickness 0.1524)
				)
			)
		)
		(property "Device Type" "R402H14"
			(at 0.064008 -5.517896 270)
			(unlocked yes)
			(layer "F.Fab")
			(hide yes)
			(effects
				(font
					(size 1.016 1.016)
					(thickness 0.1524)
				)
			)
		)
		(duplicate_pad_numbers_are_jumpers no)
		(fp_line
			(start -0.508 -0.9398)
			(end -0.508 0.9398)
			(stroke
				(width 0.1524)
				(type default)
			)
			(layer "F.SilkS")
		)
		(fp_line
			(start 0.508 -0.9398)
			(end -0.508 -0.9398)
			(stroke
				(width 0.1524)
				(type default)
			)
			(layer "F.SilkS")
		)
		(fp_rect
			(start -0.508 0.9398)
			(end 0.508 -0.9398)
			(stroke
				(width 0)
				(type default)
			)
			(fill no)
			(layer "F.CrtYd")
		)
		(fp_rect
			(start -0.508 0.9398)
			(end 0.508 -0.9398)
			(stroke
				(width 0)
				(type default)
			)
			(fill no)
			(layer "F.Fab")
		)
		(pad "1" smd custom
			(at 0 -0.4445 270)
			(size 0.1397 0.1397)
			(layers "F.Cu" "F.Mask" "F.Paste")
			(net "MB0_CM_SENSE_R1_N")
			(options
				(clearance outline)
				(anchor circle)
			)
			(primitives
				(gr_poly
					(pts
						(arc
							(start -0.1778 -0.2794)
							(mid -0.249642 -0.249642)
							(end -0.2794 -0.1778)
						)
						(arc
							(start -0.2794 0.1778)
							(mid -0.249642 0.249642)
							(end -0.1778 0.2794)
						)
						(arc
							(start 0.1778 0.2794)
							(mid 0.249642 0.249642)
							(end 0.2794 0.1778)
						)
						(arc
							(start 0.2794 -0.1778)
							(mid 0.249642 -0.249642)
							(end 0.1778 -0.2794)
						)
					)
					(width 0)
					(fill yes)
				)
			)
		)
		(pad "2" smd custom
			(at 0 0.4445 270)
			(size 0.1397 0.1397)
			(layers "F.Cu" "F.Mask" "F.Paste")
			(net "ADM1278_HS_N")
			(options
				(clearance outline)
				(anchor circle)
			)
			(primitives
				(gr_poly
					(pts
						(arc
							(start -0.1778 -0.2794)
							(mid -0.249642 -0.249642)
							(end -0.2794 -0.1778)
						)
						(arc
							(start -0.2794 0.1778)
							(mid -0.249642 0.249642)
							(end -0.1778 0.2794)
						)
						(arc
							(start 0.1778 0.2794)
							(mid 0.249642 0.249642)
							(end 0.2794 0.1778)
						)
						(arc
							(start 0.2794 -0.1778)
							(mid 0.249642 -0.249642)
							(end 0.1778 -0.2794)
						)
					)
					(width 0)
					(fill yes)
				)
			)
		)
	)
	(footprint ""
		(layer "F.Cu")
		(at 276.607016 -10.384282 90)
		(property "Reference" "R2902"
			(at 0 0 90)
			(layer "F.SilkS")
			(hide yes)
			(effects
				(font
					(size 1.27 1.27)
				)
			)
		)
		(property "Value" "0R2J-2-GP"
			(at 0.064008 -3.993896 90)
			(unlocked yes)
			(layer "F.Fab")
			(hide yes)
			(effects
				(font
					(size 1.016 1.016)
					(thickness 0.1524)
				)
			)
		)
		(property "Device Type" "R402H16"
			(at 0.064008 -5.517896 90)
			(unlocked yes)
			(layer "F.Fab")
			(hide yes)
			(effects
				(font
					(size 1.016 1.016)
					(thickness 0.1524)
				)
			)
		)
		(duplicate_pad_numbers_are_jumpers no)
		(fp_line
			(start 0.508 -0.9398)
			(end -0.508 -0.9398)
			(stroke
				(width 0.1524)
				(type default)
			)
			(layer "F.SilkS")
		)
		(fp_line
			(start -0.508 -0.9398)
			(end -0.508 0.9398)
			(stroke
				(width 0.1524)
				(type default)
			)
			(layer "F.SilkS")
		)
		(fp_rect
			(start -0.508 0.9398)
			(end 0.508 -0.9398)
			(stroke
				(width 0)
				(type default)
			)
			(fill no)
			(layer "F.CrtYd")
		)
		(fp_rect
			(start -0.508 0.9398)
			(end 0.508 -0.9398)
			(stroke
				(width 0)
				(type default)
			)
			(fill no)
			(layer "F.Fab")
		)
		(pad "1" smd custom
			(at 0 -0.4445 90)
			(size 0.1397 0.1397)
			(layers "F.Cu" "F.Mask" "F.Paste")
			(net "CBL_PRSNT_N_5")
			(options
				(clearance outline)
				(anchor circle)
			)
			(primitives
				(gr_poly
					(pts
						(arc
							(start -0.1778 -0.2794)
							(mid -0.249642 -0.249642)
							(end -0.2794 -0.1778)
						)
						(arc
							(start -0.2794 0.1778)
							(mid -0.249642 0.249642)
							(end -0.1778 0.2794)
						)
						(arc
							(start 0.1778 0.2794)
							(mid 0.249642 0.249642)
							(end 0.2794 0.1778)
						)
						(arc
							(start 0.2794 -0.1778)
							(mid 0.249642 -0.249642)
							(end 0.1778 -0.2794)
						)
					)
					(width 0)
					(fill yes)
				)
			)
		)
		(pad "2" smd custom
			(at 0 0.4445 90)
			(size 0.1397 0.1397)
			(layers "F.Cu" "F.Mask" "F.Paste")
			(net "8644_CBL_PRSNT_R_5")
			(options
				(clearance outline)
				(anchor circle)
			)
			(primitives
				(gr_poly
					(pts
						(arc
							(start -0.1778 -0.2794)
							(mid -0.249642 -0.249642)
							(end -0.2794 -0.1778)
						)
						(arc
							(start -0.2794 0.1778)
							(mid -0.249642 0.249642)
							(end -0.1778 0.2794)
						)
						(arc
							(start 0.1778 0.2794)
							(mid 0.249642 0.249642)
							(end 0.2794 0.1778)
						)
						(arc
							(start 0.2794 -0.1778)
							(mid 0.249642 -0.249642)
							(end 0.1778 -0.2794)
						)
					)
					(width 0)
					(fill yes)
				)
			)
		)
	)
	(footprint ""
		(layer "F.Cu")
		(at 58.928 -149.86 -90)
		(property "Reference" "R162"
			(at 0 0 270)
			(layer "F.SilkS")
			(hide yes)
			(effects
				(font
					(size 1.27 1.27)
				)
			)
		)
		(property "Value" "0R2J-2-GP"
			(at 0.064008 -3.993896 270)
			(unlocked yes)
			(layer "F.Fab")
			(hide yes)
			(effects
				(font
					(size 1.016 1.016)
					(thickness 0.1524)
				)
			)
		)
		(property "Device Type" "R402H16"
			(at 0.064008 -5.517896 270)
			(unlocked yes)
			(layer "F.Fab")
			(hide yes)
			(effects
				(font
					(size 1.016 1.016)
					(thickness 0.1524)
				)
			)
		)
		(duplicate_pad_numbers_are_jumpers no)
		(fp_line
			(start -0.508 -0.9398)
			(end -0.508 0.9398)
			(stroke
				(width 0.1524)
				(type default)
			)
			(layer "F.SilkS")
		)
		(fp_line
			(start 0.508 -0.9398)
			(end -0.508 -0.9398)
			(stroke
				(width 0.1524)
				(type default)
			)
			(layer "F.SilkS")
		)
		(fp_rect
			(start -0.508 0.9398)
			(end 0.508 -0.9398)
			(stroke
				(width 0)
				(type default)
			)
			(fill no)
			(layer "F.CrtYd")
		)
		(fp_rect
			(start -0.508 0.9398)
			(end 0.508 -0.9398)
			(stroke
				(width 0)
				(type default)
			)
			(fill no)
			(layer "F.Fab")
		)
		(pad "1" smd custom
			(at 0 -0.4445 270)
			(size 0.1397 0.1397)
			(layers "F.Cu" "F.Mask" "F.Paste")
			(net "BMC_I2C5_D_PEB_SCL")
			(options
				(clearance outline)
				(anchor circle)
			)
			(primitives
				(gr_poly
					(pts
						(arc
							(start -0.1778 -0.2794)
							(mid -0.249642 -0.249642)
							(end -0.2794 -0.1778)
						)
						(arc
							(start -0.2794 0.1778)
							(mid -0.249642 0.249642)
							(end -0.1778 0.2794)
						)
						(arc
							(start 0.1778 0.2794)
							(mid 0.249642 0.249642)
							(end 0.2794 0.1778)
						)
						(arc
							(start 0.2794 -0.1778)
							(mid 0.249642 -0.249642)
							(end 0.1778 -0.2794)
						)
					)
					(width 0)
					(fill yes)
				)
			)
		)
		(pad "2" smd custom
			(at 0 0.4445 270)
			(size 0.1397 0.1397)
			(layers "F.Cu" "F.Mask" "F.Paste")
			(net "TEMP_2_SCL")
			(options
				(clearance outline)
				(anchor circle)
			)
			(primitives
				(gr_poly
					(pts
						(arc
							(start -0.1778 -0.2794)
							(mid -0.249642 -0.249642)
							(end -0.2794 -0.1778)
						)
						(arc
							(start -0.2794 0.1778)
							(mid -0.249642 0.249642)
							(end -0.1778 0.2794)
						)
						(arc
							(start 0.1778 0.2794)
							(mid 0.249642 0.249642)
							(end 0.2794 0.1778)
						)
						(arc
							(start 0.2794 -0.1778)
							(mid 0.249642 -0.249642)
							(end 0.1778 -0.2794)
						)
					)
					(width 0)
					(fill yes)
				)
			)
		)
	)
	(footprint ""
		(layer "F.Cu")
		(at 37.084 -93.726 180)
		(property "Reference" "R49"
			(at 0 0 180)
			(layer "F.SilkS")
			(hide yes)
			(effects
				(font
					(size 1.27 1.27)
				)
			)
		)
		(property "Value" "0R2J-2-GP"
			(at 0.064008 -3.993896 180)
			(unlocked yes)
			(layer "F.Fab")
			(hide yes)
			(effects
				(font
					(size 1.016 1.016)
					(thickness 0.1524)
				)
			)
		)
		(property "Device Type" "R402H16"
			(at 0.064008 -5.517896 180)
			(unlocked yes)
			(layer "F.Fab")
			(hide yes)
			(effects
				(font
					(size 1.016 1.016)
					(thickness 0.1524)
				)
			)
		)
		(duplicate_pad_numbers_are_jumpers no)
		(fp_line
			(start 0.508 -0.9398)
			(end -0.508 -0.9398)
			(stroke
				(width 0.1524)
				(type default)
			)
			(layer "F.SilkS")
		)
		(fp_line
			(start -0.508 -0.9398)
			(end -0.508 0.9398)
			(stroke
				(width 0.1524)
				(type default)
			)
			(layer "F.SilkS")
		)
		(fp_rect
			(start -0.508 0.9398)
			(end 0.508 -0.9398)
			(stroke
				(width 0)
				(type default)
			)
			(fill no)
			(layer "F.CrtYd")
		)
		(fp_rect
			(start -0.508 0.9398)
			(end 0.508 -0.9398)
			(stroke
				(width 0)
				(type default)
			)
			(fill no)
			(layer "F.Fab")
		)
		(pad "1" smd custom
			(at 0 -0.4445 180)
			(size 0.1397 0.1397)
			(layers "F.Cu" "F.Mask" "F.Paste")
			(net "NVM_SO_R")
			(options
				(clearance outline)
				(anchor circle)
			)
			(primitives
				(gr_poly
					(pts
						(arc
							(start -0.1778 -0.2794)
							(mid -0.249642 -0.249642)
							(end -0.2794 -0.1778)
						)
						(arc
							(start -0.2794 0.1778)
							(mid -0.249642 0.249642)
							(end -0.1778 0.2794)
						)
						(arc
							(start 0.1778 0.2794)
							(mid 0.249642 0.249642)
							(end 0.2794 0.1778)
						)
						(arc
							(start 0.2794 -0.1778)
							(mid 0.249642 -0.249642)
							(end 0.1778 -0.2794)
						)
					)
					(width 0)
					(fill yes)
				)
			)
		)
		(pad "2" smd custom
			(at 0 0.4445 180)
			(size 0.1397 0.1397)
			(layers "F.Cu" "F.Mask" "F.Paste")
			(net "I2C_MUX_3A")
			(options
				(clearance outline)
				(anchor circle)
			)
			(primitives
				(gr_poly
					(pts
						(arc
							(start -0.1778 -0.2794)
							(mid -0.249642 -0.249642)
							(end -0.2794 -0.1778)
						)
						(arc
							(start -0.2794 0.1778)
							(mid -0.249642 0.249642)
							(end -0.1778 0.2794)
						)
						(arc
							(start 0.1778 0.2794)
							(mid 0.249642 0.249642)
							(end 0.2794 0.1778)
						)
						(arc
							(start 0.2794 -0.1778)
							(mid 0.249642 -0.249642)
							(end 0.1778 -0.2794)
						)
					)
					(width 0)
					(fill yes)
				)
			)
		)
	)
	(footprint ""
		(layer "F.Cu")
		(at 37.193474 -114.751612 180)
		(property "Reference" "R556"
			(at 0 0 180)
			(layer "F.SilkS")
			(hide yes)
			(effects
				(font
					(size 1.27 1.27)
				)
			)
		)
		(property "Value" "10KR2F-2-GP"
			(at 0.064008 -3.993896 180)
			(unlocked yes)
			(layer "F.Fab")
			(hide yes)
			(effects
				(font
					(size 1.016 1.016)
					(thickness 0.1524)
				)
			)
		)
		(property "Device Type" "R402H16"
			(at 0.064008 -5.517896 180)
			(unlocked yes)
			(layer "F.Fab")
			(hide yes)
			(effects
				(font
					(size 1.016 1.016)
					(thickness 0.1524)
				)
			)
		)
		(duplicate_pad_numbers_are_jumpers no)
		(fp_line
			(start 0.508 -0.9398)
			(end -0.508 -0.9398)
			(stroke
				(width 0.1524)
				(type default)
			)
			(layer "F.SilkS")
		)
		(fp_line
			(start -0.508 -0.9398)
			(end -0.508 0.9398)
			(stroke
				(width 0.1524)
				(type default)
			)
			(layer "F.SilkS")
		)
		(fp_rect
			(start -0.508 0.9398)
			(end 0.508 -0.9398)
			(stroke
				(width 0)
				(type default)
			)
			(fill no)
			(layer "F.CrtYd")
		)
		(fp_rect
			(start -0.508 0.9398)
			(end 0.508 -0.9398)
			(stroke
				(width 0)
				(type default)
			)
			(fill no)
			(layer "F.Fab")
		)
		(pad "1" smd custom
			(at 0 -0.4445 180)
			(size 0.1397 0.1397)
			(layers "F.Cu" "F.Mask" "F.Paste")
			(net "GND")
			(options
				(clearance outline)
				(anchor circle)
			)
			(primitives
				(gr_poly
					(pts
						(arc
							(start -0.1778 -0.2794)
							(mid -0.249642 -0.249642)
							(end -0.2794 -0.1778)
						)
						(arc
							(start -0.2794 0.1778)
							(mid -0.249642 0.249642)
							(end -0.1778 0.2794)
						)
						(arc
							(start 0.1778 0.2794)
							(mid 0.249642 0.249642)
							(end 0.2794 0.1778)
						)
						(arc
							(start 0.2794 -0.1778)
							(mid 0.249642 -0.249642)
							(end 0.1778 -0.2794)
						)
					)
					(width 0)
					(fill yes)
				)
			)
		)
		(pad "2" smd custom
			(at 0 0.4445 180)
			(size 0.1397 0.1397)
			(layers "F.Cu" "F.Mask" "F.Paste")
			(net "RMII_BMC_CRS_DV")
			(options
				(clearance outline)
				(anchor circle)
			)
			(primitives
				(gr_poly
					(pts
						(arc
							(start -0.1778 -0.2794)
							(mid -0.249642 -0.249642)
							(end -0.2794 -0.1778)
						)
						(arc
							(start -0.2794 0.1778)
							(mid -0.249642 0.249642)
							(end -0.1778 0.2794)
						)
						(arc
							(start 0.1778 0.2794)
							(mid 0.249642 0.249642)
							(end 0.2794 0.1778)
						)
						(arc
							(start 0.2794 -0.1778)
							(mid 0.249642 -0.249642)
							(end 0.1778 -0.2794)
						)
					)
					(width 0)
					(fill yes)
				)
			)
		)
	)
	(footprint ""
		(layer "F.Cu")
		(at 70.715124 -195.681092)
		(property "Reference" "R7913"
			(at 0 0 0)
			(layer "F.SilkS")
			(hide yes)
			(effects
				(font
					(size 1.27 1.27)
				)
			)
		)
		(property "Value" "0R2J-2-GP"
			(at 0.064008 -3.993896 0)
			(unlocked yes)
			(layer "F.Fab")
			(hide yes)
			(effects
				(font
					(size 1.016 1.016)
					(thickness 0.1524)
				)
			)
		)
		(property "Device Type" "R402H16"
			(at 0.064008 -5.517896 0)
			(unlocked yes)
			(layer "F.Fab")
			(hide yes)
			(effects
				(font
					(size 1.016 1.016)
					(thickness 0.1524)
				)
			)
		)
		(duplicate_pad_numbers_are_jumpers no)
		(fp_line
			(start -0.508 -0.9398)
			(end -0.508 0.9398)
			(stroke
				(width 0.1524)
				(type default)
			)
			(layer "F.SilkS")
		)
		(fp_line
			(start 0.508 -0.9398)
			(end -0.508 -0.9398)
			(stroke
				(width 0.1524)
				(type default)
			)
			(layer "F.SilkS")
		)
		(fp_rect
			(start -0.508 0.9398)
			(end 0.508 -0.9398)
			(stroke
				(width 0)
				(type default)
			)
			(fill no)
			(layer "F.CrtYd")
		)
		(fp_rect
			(start -0.508 0.9398)
			(end 0.508 -0.9398)
			(stroke
				(width 0)
				(type default)
			)
			(fill no)
			(layer "F.Fab")
		)
		(pad "1" smd custom
			(at 0 -0.4445)
			(size 0.1397 0.1397)
			(layers "F.Cu" "F.Mask" "F.Paste")
			(net "TWI_SCL1")
			(options
				(clearance outline)
				(anchor circle)
			)
			(primitives
				(gr_poly
					(pts
						(arc
							(start -0.1778 -0.2794)
							(mid -0.249642 -0.249642)
							(end -0.2794 -0.1778)
						)
						(arc
							(start -0.2794 0.1778)
							(mid -0.249642 0.249642)
							(end -0.1778 0.2794)
						)
						(arc
							(start 0.1778 0.2794)
							(mid 0.249642 0.249642)
							(end 0.2794 0.1778)
						)
						(arc
							(start 0.2794 -0.1778)
							(mid 0.249642 -0.249642)
							(end 0.1778 -0.2794)
						)
					)
					(width 0)
					(fill yes)
				)
			)
		)
		(pad "2" smd custom
			(at 0 0.4445)
			(size 0.1397 0.1397)
			(layers "F.Cu" "F.Mask" "F.Paste")
			(net "I2C_GPIO_SCL_1")
			(options
				(clearance outline)
				(anchor circle)
			)
			(primitives
				(gr_poly
					(pts
						(arc
							(start -0.1778 -0.2794)
							(mid -0.249642 -0.249642)
							(end -0.2794 -0.1778)
						)
						(arc
							(start -0.2794 0.1778)
							(mid -0.249642 0.249642)
							(end -0.1778 0.2794)
						)
						(arc
							(start 0.1778 0.2794)
							(mid 0.249642 0.249642)
							(end 0.2794 0.1778)
						)
						(arc
							(start 0.2794 -0.1778)
							(mid 0.249642 -0.249642)
							(end 0.1778 -0.2794)
						)
					)
					(width 0)
					(fill yes)
				)
			)
		)
	)
)
